# BASEBOARD_FAB2 (Tioga Pass) — schematic netlist excerpt (pin names and nets, part order shuffled) for the footprints in the layout excerpt that follows; sources: Cadence DE-HDL packaged netlist, KiCad conversion of Wiwynn_Tioga_Pass_MB.brd

J9G1  CONN12_C73564003  CONN  pkg PIP  page 137
  IO1  = PU_UV_HIGH_SET
  IO2  = TP_RST_RTCRST_N
  IO3  = UV_HIGH_SET
  IO4  = RST_RTCRST_N
  IO5  = PD_UV_HIGH_SET
  IO6  = PD_RST_RTCRST_N
  IO7  = TP_IE_DEBUG_MODE
  IO8  = PU_SPI_BMC_BT_CS0_N
  IO9  = FM_UART_PRES_N
  IO10  = SPI_BMC_BT_CS0_N
  IO11  = PD_IE_DEBUG_MODE
  IO12  = PD_SPI_BMC_BT_CS0_N

(kicad_pcb
	(version 20260206)
	(generator "pcbnew")
	(generator_version "10.0")
	(general
		(thickness 1.6)
		(legacy_teardrops no)
	)
	(paper "A4")
	(title_block
		(title "Wiwynn_Tioga_Pass_MB.brd")
		(comment 1 "Tioga Pass / footprint 1749 of 4770 (J9G1), pads 1-12 of 12")
	)
	(layers
		(0 "F.Cu" signal "TOP")
		(4 "In1.Cu" signal "L2GND")
		(6 "In2.Cu" signal "L3")
		(8 "In3.Cu" signal "L4GND")
		(10 "In4.Cu" signal "L5")
		(12 "In5.Cu" signal "L6GND")
		(14 "In6.Cu" signal "L7VCC")
		(16 "In7.Cu" signal "L8VCC")
		(18 "In8.Cu" signal "L9GND")
		(20 "In9.Cu" signal "L10")
		(22 "In10.Cu" signal "L11GND")
		(24 "In11.Cu" signal "L12")
		(26 "In12.Cu" signal "L13GND")
		(2 "B.Cu" signal "BOTTOM")
		(9 "F.Adhes" user "F.Adhesive")
		(11 "B.Adhes" user "B.Adhesive")
		(13 "F.Paste" user "Package Geometry/Pastemask Top")
		(15 "B.Paste" user "Package Geometry/Pastemask Bottom")
		(5 "F.SilkS" user "Ref Des/Silkscreen Top")
		(7 "B.SilkS" user "Ref Des/Silkscreen Bottom")
		(1 "F.Mask" user "Board Geometry/Soldermask Top")
		(3 "B.Mask" user "Board Geometry/Soldermask Bottom")
		(17 "Dwgs.User" user "User.Drawings")
		(19 "Cmts.User" user "User.Comments")
		(21 "Eco1.User" user "User.Eco1")
		(23 "Eco2.User" user "User.Eco2")
		(25 "Edge.Cuts" user "Board Geometry/Outline")
		(27 "Margin" user)
		(31 "F.CrtYd" user "Package Geometry/Place Bound Top")
		(29 "B.CrtYd" user "Package Geometry/Place Bound Bottom")
		(35 "F.Fab" user "Ref Des/Assembly Top")
		(33 "B.Fab" user "Ref Des/Assembly Bottom")
	)
	(footprint ""
		(layer "F.Cu")
		(at 449.454016 3.81 90)
		(property "Reference" "J9G1"
			(at 1.524 -2.13233 90)
			(unlocked yes)
			(layer "B.SilkS")
			(effects
				(font
					(size 0.7874 0.5842)
					(thickness 0.1524)
				)
				(justify mirror)
			)
		)
		(property "Value" ""
			(at 0 0 90)
			(layer "F.Fab")
			(effects
				(font
					(size 1.27 1.27)
				)
			)
		)
		(duplicate_pad_numbers_are_jumpers no)
		(pad "1" thru_hole rect
			(at 0 0 90)
			(size 1.6256 1.6256)
			(drill 1.2446)
			(layers "*.Cu" "*.Mask")
			(remove_unused_layers no)
			(net "PU_UV_HIGH_SET")
			(clearance 0.127)
			(thermal_gap 0.127)
			(padstack
				(mode front_inner_back)
				(layer "Inner"
					(shape circle)
					(size 1.6256 1.6256)
					(clearance 0.127)
				)
				(layer "B.Cu"
					(shape rect)
					(size 1.6256 1.6256)
					(clearance 0.127)
				)
			)
		)
		(pad "2" thru_hole circle
			(at 2.54 0 90)
			(size 1.6256 1.6256)
			(drill 1.2446)
			(layers "*.Cu" "*.Mask")
			(remove_unused_layers no)
			(net "TP_RST_RTCRST_N")
			(clearance 0.127)
			(thermal_gap 0.127)
		)
		(pad "3" thru_hole circle
			(at 0 2.54 90)
			(size 1.6256 1.6256)
			(drill 1.2446)
			(layers "*.Cu" "*.Mask")
			(remove_unused_layers no)
			(net "UV_HIGH_SET")
			(clearance 0.127)
			(thermal_gap 0.127)
		)
		(pad "4" thru_hole circle
			(at 2.54 2.54 90)
			(size 1.6256 1.6256)
			(drill 1.2446)
			(layers "*.Cu" "*.Mask")
			(remove_unused_layers no)
			(net "RST_RTCRST_N")
			(clearance 0.127)
			(thermal_gap 0.127)
		)
		(pad "5" thru_hole circle
			(at 0 5.08 90)
			(size 1.6256 1.6256)
			(drill 1.2446)
			(layers "*.Cu" "*.Mask")
			(remove_unused_layers no)
			(net "PD_UV_HIGH_SET")
			(clearance 0.127)
			(thermal_gap 0.127)
		)
		(pad "6" thru_hole circle
			(at 2.54 5.08 90)
			(size 1.6256 1.6256)
			(drill 1.2446)
			(layers "*.Cu" "*.Mask")
			(remove_unused_layers no)
			(net "PD_RST_RTCRST_N")
			(clearance 0.127)
			(thermal_gap 0.127)
		)
		(pad "7" thru_hole circle
			(at 0 7.62 90)
			(size 1.6256 1.6256)
			(drill 1.2446)
			(layers "*.Cu" "*.Mask")
			(remove_unused_layers no)
			(net "TP_IE_DEBUG_MODE")
			(clearance 0.127)
			(thermal_gap 0.127)
		)
		(pad "8" thru_hole circle
			(at 2.54 7.62 90)
			(size 1.6256 1.6256)
			(drill 1.2446)
			(layers "*.Cu" "*.Mask")
			(remove_unused_layers no)
			(net "PU_SPI_BMC_BT_CS0_N")
			(clearance 0.127)
			(thermal_gap 0.127)
		)
		(pad "9" thru_hole circle
			(at 0 10.16 90)
			(size 1.6256 1.6256)
			(drill 1.2446)
			(layers "*.Cu" "*.Mask")
			(remove_unused_layers no)
			(net "FM_UART_PRES_N")
			(clearance 0.127)
			(thermal_gap 0.127)
		)
		(pad "10" thru_hole circle
			(at 2.54 10.16 90)
			(size 1.6256 1.6256)
			(drill 1.2446)
			(layers "*.Cu" "*.Mask")
			(remove_unused_layers no)
			(net "SPI_BMC_BT_CS0_N")
			(clearance 0.127)
			(thermal_gap 0.127)
		)
		(pad "11" thru_hole circle
			(at 0 12.7 90)
			(size 1.6256 1.6256)
			(drill 1.2446)
			(layers "*.Cu" "*.Mask")
			(remove_unused_layers no)
			(net "PD_IE_DEBUG_MODE")
			(clearance 0.127)
			(thermal_gap 0.127)
		)
		(pad "12" thru_hole circle
			(at 2.54 12.7 90)
			(size 1.6256 1.6256)
			(drill 1.2446)
			(layers "*.Cu" "*.Mask")
			(remove_unused_layers no)
			(net "PD_SPI_BMC_BT_CS0_N")
			(clearance 0.127)
			(thermal_gap 0.127)
		)
	)
)
